(kicad_pcb
	(version 20260206)
	(generator "pcbnew")
	(generator_version "10.0")
	(general
		(thickness 1.6)
		(legacy_teardrops no)
	)
	(paper "A4")
	(title_block
		(title "Bryce Canyon_IOM_M2_16342-2_OCP.brd")
		(comment 1 "Bryce Canyon / footprints 941-947 of 1146")
	)
	(layers
		(0 "F.Cu" signal "TOP")
		(4 "In1.Cu" signal "L2GND")
		(6 "In2.Cu" signal "L3")
		(8 "In3.Cu" signal "L4VCC")
		(10 "In4.Cu" signal "L5VCC")
		(12 "In5.Cu" signal "L6")
		(14 "In6.Cu" signal "L7GND")
		(2 "B.Cu" signal "BOTTOM")
		(9 "F.Adhes" user "F.Adhesive")
		(11 "B.Adhes" user "B.Adhesive")
		(13 "F.Paste" user "Package Geometry/Pastemask Top")
		(15 "B.Paste" user "Package Geometry/Pastemask Bottom")
		(5 "F.SilkS" user "Ref Des/Silkscreen Top")
		(7 "B.SilkS" user "Ref Des/Silkscreen Bottom")
		(1 "F.Mask" user "Board Geometry/Soldermask Top")
		(3 "B.Mask" user "Board Geometry/Soldermask Bottom")
		(17 "Dwgs.User" user "User.Drawings")
		(19 "Cmts.User" user "User.Comments")
		(21 "Eco1.User" user "User.Eco1")
		(23 "Eco2.User" user "User.Eco2")
		(25 "Edge.Cuts" user "Board Geometry/Outline")
		(27 "Margin" user)
		(31 "F.CrtYd" user "Package Geometry/Place Bound Top")
		(29 "B.CrtYd" user "Package Geometry/Place Bound Bottom")
		(35 "F.Fab" user "Ref Des/Assembly Top")
		(33 "B.Fab" user "Ref Des/Assembly Bottom")
	)
	(footprint ""
		(layer "B.Cu")
		(at 69.56933 -144.691608)
		(property "Reference" "R194"
			(at 0 0 0)
			(layer "B.SilkS")
			(hide yes)
			(effects
				(font
					(size 1.27 1.27)
				)
				(justify mirror)
			)
		)
		(property "Value" "20KR2F-L-GP"
			(at -0.064008 -3.993896 0)
			(unlocked yes)
			(layer "B.Fab")
			(hide yes)
			(effects
				(font
					(size 1.016 1.016)
					(thickness 0.1524)
				)
				(justify mirror)
			)
		)
		(property "Device Type" "R402H16"
			(at -0.064008 -5.517896 0)
			(unlocked yes)
			(layer "B.Fab")
			(hide yes)
			(effects
				(font
					(size 1.016 1.016)
					(thickness 0.1524)
				)
				(justify mirror)
			)
		)
		(duplicate_pad_numbers_are_jumpers no)
		(fp_line
			(start -0.508 -0.9398)
			(end 0.508 -0.9398)
			(stroke
				(width 0.1524)
				(type default)
			)
			(layer "B.SilkS")
		)
		(fp_line
			(start 0.508 -0.9398)
			(end 0.508 0.9398)
			(stroke
				(width 0.1524)
				(type default)
			)
			(layer "B.SilkS")
		)
		(fp_rect
			(start 0.508 0.9398)
			(end -0.508 -0.9398)
			(stroke
				(width 0)
				(type default)
			)
			(fill no)
			(layer "B.CrtYd")
		)
		(fp_rect
			(start 0.508 0.9398)
			(end -0.508 -0.9398)
			(stroke
				(width 0)
				(type default)
			)
			(fill no)
			(layer "B.Fab")
		)
		(pad "1" smd custom
			(at 0 -0.4445 180)
			(size 0.1397 0.1397)
			(layers "B.Cu" "B.Mask" "B.Paste")
			(net "P3V3_STBY")
			(options
				(clearance outline)
				(anchor circle)
			)
			(primitives
				(gr_poly
					(pts
						(arc
							(start -0.1778 0.2794)
							(mid -0.249642 0.249642)
							(end -0.2794 0.1778)
						)
						(arc
							(start -0.2794 -0.1778)
							(mid -0.249642 -0.249642)
							(end -0.1778 -0.2794)
						)
						(arc
							(start 0.1778 -0.2794)
							(mid 0.249642 -0.249642)
							(end 0.2794 -0.1778)
						)
						(arc
							(start 0.2794 0.1778)
							(mid 0.249642 0.249642)
							(end 0.1778 0.2794)
						)
					)
					(width 0)
					(fill yes)
				)
			)
		)
		(pad "2" smd custom
			(at 0 0.4445 180)
			(size 0.1397 0.1397)
			(layers "B.Cu" "B.Mask" "B.Paste")
			(net "I2C_DEBUG_SDA_L")
			(options
				(clearance outline)
				(anchor circle)
			)
			(primitives
				(gr_poly
					(pts
						(arc
							(start -0.1778 0.2794)
							(mid -0.249642 0.249642)
							(end -0.2794 0.1778)
						)
						(arc
							(start -0.2794 -0.1778)
							(mid -0.249642 -0.249642)
							(end -0.1778 -0.2794)
						)
						(arc
							(start 0.1778 -0.2794)
							(mid 0.249642 -0.249642)
							(end 0.2794 -0.1778)
						)
						(arc
							(start 0.2794 0.1778)
							(mid 0.249642 0.249642)
							(end 0.1778 0.2794)
						)
					)
					(width 0)
					(fill yes)
				)
			)
		)
	)
	(footprint ""
		(layer "B.Cu")
		(at 78.4098 -130.4798)
		(property "Reference" "C502"
			(at 0 0 0)
			(layer "B.SilkS")
			(hide yes)
			(effects
				(font
					(size 1.27 1.27)
				)
				(justify mirror)
			)
		)
		(property "Value" "SCD1U16V2KX-3GP"
			(at -1.1811 -2.7051 0)
			(unlocked yes)
			(layer "B.Fab")
			(hide yes)
			(effects
				(font
					(size 1.016 1.016)
					(thickness 0.1524)
				)
				(justify mirror)
			)
		)
		(property "Device Type" "C402H22"
			(at -1.1811 -4.2291 0)
			(unlocked yes)
			(layer "B.Fab")
			(hide yes)
			(effects
				(font
					(size 1.016 1.016)
					(thickness 0.1524)
				)
				(justify mirror)
			)
		)
		(duplicate_pad_numbers_are_jumpers no)
		(fp_rect
			(start 0.4318 0.9525)
			(end -0.4318 -0.9525)
			(stroke
				(width 0)
				(type default)
			)
			(fill no)
			(layer "B.CrtYd")
		)
		(fp_rect
			(start 0.4318 0.9525)
			(end -0.4318 -0.9525)
			(stroke
				(width 0)
				(type default)
			)
			(fill no)
			(layer "B.Fab")
		)
		(pad "1" smd custom
			(at 0 -0.4445 180)
			(size 0.1524 0.1524)
			(layers "B.Cu" "B.Mask" "B.Paste")
			(net "P3V3_STBY")
			(options
				(clearance outline)
				(anchor circle)
			)
			(primitives
				(gr_poly
					(pts
						(arc
							(start 0.3048 0.2032)
							(mid 0.275042 0.275042)
							(end 0.2032 0.3048)
						)
						(arc
							(start -0.2032 0.3048)
							(mid -0.275042 0.275042)
							(end -0.3048 0.2032)
						)
						(arc
							(start -0.3048 -0.2032)
							(mid -0.275042 -0.275042)
							(end -0.2032 -0.3048)
						)
						(arc
							(start 0.2032 -0.3048)
							(mid 0.275042 -0.275042)
							(end 0.3048 -0.2032)
						)
					)
					(width 0)
					(fill yes)
				)
			)
		)
		(pad "2" smd custom
			(at 0 0.4445 180)
			(size 0.1524 0.1524)
			(layers "B.Cu" "B.Mask" "B.Paste")
			(net "GND")
			(options
				(clearance outline)
				(anchor circle)
			)
			(primitives
				(gr_poly
					(pts
						(arc
							(start 0.3048 0.2032)
							(mid 0.275042 0.275042)
							(end 0.2032 0.3048)
						)
						(arc
							(start -0.2032 0.3048)
							(mid -0.275042 0.275042)
							(end -0.3048 0.2032)
						)
						(arc
							(start -0.3048 -0.2032)
							(mid -0.275042 -0.275042)
							(end -0.2032 -0.3048)
						)
						(arc
							(start 0.2032 -0.3048)
							(mid 0.275042 -0.275042)
							(end 0.3048 -0.2032)
						)
					)
					(width 0)
					(fill yes)
				)
			)
		)
	)
	(footprint ""
		(layer "B.Cu")
		(at 42.357294 -125.48108)
		(property "Reference" "R364"
			(at 0 0 0)
			(layer "B.SilkS")
			(hide yes)
			(effects
				(font
					(size 1.27 1.27)
				)
				(justify mirror)
			)
		)
		(property "Value" "4K7R2F-GP"
			(at -0.064008 -3.993896 0)
			(unlocked yes)
			(layer "B.Fab")
			(hide yes)
			(effects
				(font
					(size 1.016 1.016)
					(thickness 0.1524)
				)
				(justify mirror)
			)
		)
		(property "Device Type" "R402H16"
			(at -0.064008 -5.517896 0)
			(unlocked yes)
			(layer "B.Fab")
			(hide yes)
			(effects
				(font
					(size 1.016 1.016)
					(thickness 0.1524)
				)
				(justify mirror)
			)
		)
		(duplicate_pad_numbers_are_jumpers no)
		(fp_line
			(start -0.508 -0.9398)
			(end 0.508 -0.9398)
			(stroke
				(width 0.1524)
				(type default)
			)
			(layer "B.SilkS")
		)
		(fp_line
			(start 0.508 -0.9398)
			(end 0.508 0.9398)
			(stroke
				(width 0.1524)
				(type default)
			)
			(layer "B.SilkS")
		)
		(fp_rect
			(start 0.508 0.9398)
			(end -0.508 -0.9398)
			(stroke
				(width 0)
				(type default)
			)
			(fill no)
			(layer "B.CrtYd")
		)
		(fp_rect
			(start 0.508 0.9398)
			(end -0.508 -0.9398)
			(stroke
				(width 0)
				(type default)
			)
			(fill no)
			(layer "B.Fab")
		)
		(pad "1" smd custom
			(at 0 -0.4445 180)
			(size 0.1397 0.1397)
			(layers "B.Cu" "B.Mask" "B.Paste")
			(net "FM_BMC_RESET_N")
			(options
				(clearance outline)
				(anchor circle)
			)
			(primitives
				(gr_poly
					(pts
						(arc
							(start -0.1778 0.2794)
							(mid -0.249642 0.249642)
							(end -0.2794 0.1778)
						)
						(arc
							(start -0.2794 -0.1778)
							(mid -0.249642 -0.249642)
							(end -0.1778 -0.2794)
						)
						(arc
							(start 0.1778 -0.2794)
							(mid 0.249642 -0.249642)
							(end 0.2794 -0.1778)
						)
						(arc
							(start 0.2794 0.1778)
							(mid 0.249642 0.249642)
							(end 0.1778 0.2794)
						)
					)
					(width 0)
					(fill yes)
				)
			)
		)
		(pad "2" smd custom
			(at 0 0.4445 180)
			(size 0.1397 0.1397)
			(layers "B.Cu" "B.Mask" "B.Paste")
			(net "GND")
			(options
				(clearance outline)
				(anchor circle)
			)
			(primitives
				(gr_poly
					(pts
						(arc
							(start -0.1778 0.2794)
							(mid -0.249642 0.249642)
							(end -0.2794 0.1778)
						)
						(arc
							(start -0.2794 -0.1778)
							(mid -0.249642 -0.249642)
							(end -0.1778 -0.2794)
						)
						(arc
							(start 0.1778 -0.2794)
							(mid 0.249642 -0.249642)
							(end 0.2794 -0.1778)
						)
						(arc
							(start 0.2794 0.1778)
							(mid 0.249642 0.249642)
							(end 0.1778 0.2794)
						)
					)
					(width 0)
					(fill yes)
				)
			)
		)
	)
	(footprint ""
		(layer "B.Cu")
		(at 34.8742 -127.2794 -90)
		(property "Reference" "U104"
			(at 0 0 90)
			(layer "B.SilkS")
			(hide yes)
			(effects
				(font
					(size 1.27 1.27)
				)
				(justify mirror)
			)
		)
		(property "Value" "SNLVC1G126DCKR-GP"
			(at 2.3368 -8.6868 270)
			(unlocked yes)
			(layer "B.Fab")
			(hide yes)
			(effects
				(font
					(size 1.016 1.016)
					(thickness 0.1524)
				)
				(justify mirror)
			)
		)
		(property "Device Type" "SC70-5H44"
			(at 2.3114 -10.414 270)
			(unlocked yes)
			(layer "B.Fab")
			(hide yes)
			(effects
				(font
					(size 1.016 1.016)
					(thickness 0.1524)
				)
				(justify mirror)
			)
		)
		(duplicate_pad_numbers_are_jumpers no)
		(fp_line
			(start -1.27 1.7018)
			(end 1.27 1.7018)
			(stroke
				(width 0.1524)
				(type default)
			)
			(layer "B.SilkS")
		)
		(fp_line
			(start 1.27 1.7018)
			(end 1.27 -1.7018)
			(stroke
				(width 0.1524)
				(type default)
			)
			(layer "B.SilkS")
		)
		(fp_line
			(start -1.27 -1.7018)
			(end -1.27 1.7018)
			(stroke
				(width 0.1524)
				(type default)
			)
			(layer "B.SilkS")
		)
		(fp_line
			(start 1.27 -1.7018)
			(end -1.27 -1.7018)
			(stroke
				(width 0.1524)
				(type default)
			)
			(layer "B.SilkS")
		)
		(fp_line
			(start -1.3843 -1.8034)
			(end -1.3843 -1.1176)
			(stroke
				(width 0.3302)
				(type default)
			)
			(layer "B.SilkS")
		)
		(fp_line
			(start -0.6604 -1.8034)
			(end -1.3843 -1.8034)
			(stroke
				(width 0.3302)
				(type default)
			)
			(layer "B.SilkS")
		)
		(fp_rect
			(start 1.524 1.9558)
			(end -1.524 -1.9558)
			(stroke
				(width 0)
				(type default)
			)
			(fill no)
			(layer "B.CrtYd")
		)
		(fp_poly
			(pts
				(xy 1.524 -1.9558) (xy -1.524 -1.9558) (xy -1.524 1.9558) (xy 1.524 1.9558)
			)
			(stroke
				(width 0)
				(type default)
			)
			(fill no)
			(layer "B.Fab")
		)
		(pad "1" smd rect
			(at -0.65024 -0.8255 90)
			(size 0.4064 1.2192)
			(layers "B.Cu" "B.Mask" "B.Paste")
			(net "U104_EN")
		)
		(pad "2" smd rect
			(at 0 -0.8255 90)
			(size 0.4064 1.2192)
			(layers "B.Cu" "B.Mask" "B.Paste")
			(net "SYS_RESET_N_OUT")
		)
		(pad "3" smd rect
			(at 0.65024 -0.8255 90)
			(size 0.4064 1.2192)
			(layers "B.Cu" "B.Mask" "B.Paste")
			(net "GND")
		)
		(pad "4" smd rect
			(at 0.65024 0.8255 90)
			(size 0.4064 1.2192)
			(layers "B.Cu" "B.Mask" "B.Paste")
			(net "SYS_RESET_N")
		)
		(pad "5" smd rect
			(at -0.65024 0.8255 90)
			(size 0.4064 1.2192)
			(layers "B.Cu" "B.Mask" "B.Paste")
			(net "P3V3_STBY")
		)
	)
	(footprint ""
		(layer "B.Cu")
		(at 191.332866 -136.834372 90)
		(property "Reference" "R803"
			(at 0 0 90)
			(layer "B.SilkS")
			(hide yes)
			(effects
				(font
					(size 1.27 1.27)
				)
				(justify mirror)
			)
		)
		(property "Value" "4K7R2F-GP"
			(at -0.064008 -3.993896 90)
			(unlocked yes)
			(layer "B.Fab")
			(hide yes)
			(effects
				(font
					(size 1.016 1.016)
					(thickness 0.1524)
				)
				(justify mirror)
			)
		)
		(property "Device Type" "R402H16"
			(at -0.064008 -5.517896 90)
			(unlocked yes)
			(layer "B.Fab")
			(hide yes)
			(effects
				(font
					(size 1.016 1.016)
					(thickness 0.1524)
				)
				(justify mirror)
			)
		)
		(duplicate_pad_numbers_are_jumpers no)
		(fp_line
			(start 0.508 -0.9398)
			(end 0.508 0.9398)
			(stroke
				(width 0.1524)
				(type default)
			)
			(layer "B.SilkS")
		)
		(fp_line
			(start -0.508 -0.9398)
			(end 0.508 -0.9398)
			(stroke
				(width 0.1524)
				(type default)
			)
			(layer "B.SilkS")
		)
		(fp_rect
			(start 0.508 0.9398)
			(end -0.508 -0.9398)
			(stroke
				(width 0)
				(type default)
			)
			(fill no)
			(layer "B.CrtYd")
		)
		(fp_rect
			(start 0.508 0.9398)
			(end -0.508 -0.9398)
			(stroke
				(width 0)
				(type default)
			)
			(fill no)
			(layer "B.Fab")
		)
		(pad "1" smd custom
			(at 0 -0.4445 270)
			(size 0.1397 0.1397)
			(layers "B.Cu" "B.Mask" "B.Paste")
			(net "P3V3_STBY")
			(options
				(clearance outline)
				(anchor circle)
			)
			(primitives
				(gr_poly
					(pts
						(arc
							(start -0.1778 0.2794)
							(mid -0.249642 0.249642)
							(end -0.2794 0.1778)
						)
						(arc
							(start -0.2794 -0.1778)
							(mid -0.249642 -0.249642)
							(end -0.1778 -0.2794)
						)
						(arc
							(start 0.1778 -0.2794)
							(mid 0.249642 -0.249642)
							(end 0.2794 -0.1778)
						)
						(arc
							(start 0.2794 0.1778)
							(mid 0.249642 0.249642)
							(end 0.1778 0.2794)
						)
					)
					(width 0)
					(fill yes)
				)
			)
		)
		(pad "2" smd custom
			(at 0 0.4445 270)
			(size 0.1397 0.1397)
			(layers "B.Cu" "B.Mask" "B.Paste")
			(net "M2_1_PRESENT_N")
			(options
				(clearance outline)
				(anchor circle)
			)
			(primitives
				(gr_poly
					(pts
						(arc
							(start -0.1778 0.2794)
							(mid -0.249642 0.249642)
							(end -0.2794 0.1778)
						)
						(arc
							(start -0.2794 -0.1778)
							(mid -0.249642 -0.249642)
							(end -0.1778 -0.2794)
						)
						(arc
							(start 0.1778 -0.2794)
							(mid 0.249642 -0.249642)
							(end 0.2794 -0.1778)
						)
						(arc
							(start 0.2794 0.1778)
							(mid 0.249642 0.249642)
							(end 0.1778 0.2794)
						)
					)
					(width 0)
					(fill yes)
				)
			)
		)
	)
	(footprint ""
		(layer "B.Cu")
		(at 37.465 -151.5618 -90)
		(property "Reference" "R318"
			(at 0 0 90)
			(layer "B.SilkS")
			(hide yes)
			(effects
				(font
					(size 1.27 1.27)
				)
				(justify mirror)
			)
		)
		(property "Value" "0R2J-2-GP"
			(at -0.064008 -3.993896 270)
			(unlocked yes)
			(layer "B.Fab")
			(hide yes)
			(effects
				(font
					(size 1.016 1.016)
					(thickness 0.1524)
				)
				(justify mirror)
			)
		)
		(property "Device Type" "R402H16"
			(at -0.064008 -5.517896 270)
			(unlocked yes)
			(layer "B.Fab")
			(hide yes)
			(effects
				(font
					(size 1.016 1.016)
					(thickness 0.1524)
				)
				(justify mirror)
			)
		)
		(duplicate_pad_numbers_are_jumpers no)
		(fp_line
			(start -0.508 -0.9398)
			(end 0.508 -0.9398)
			(stroke
				(width 0.1524)
				(type default)
			)
			(layer "B.SilkS")
		)
		(fp_line
			(start 0.508 -0.9398)
			(end 0.508 0.9398)
			(stroke
				(width 0.1524)
				(type default)
			)
			(layer "B.SilkS")
		)
		(fp_rect
			(start 0.508 0.9398)
			(end -0.508 -0.9398)
			(stroke
				(width 0)
				(type default)
			)
			(fill no)
			(layer "B.CrtYd")
		)
		(fp_rect
			(start 0.508 0.9398)
			(end -0.508 -0.9398)
			(stroke
				(width 0)
				(type default)
			)
			(fill no)
			(layer "B.Fab")
		)
		(pad "1" smd custom
			(at 0 -0.4445 90)
			(size 0.1397 0.1397)
			(layers "B.Cu" "B.Mask" "B.Paste")
			(net "COMP_PWR_EN_R")
			(options
				(clearance outline)
				(anchor circle)
			)
			(primitives
				(gr_poly
					(pts
						(arc
							(start -0.1778 0.2794)
							(mid -0.249642 0.249642)
							(end -0.2794 0.1778)
						)
						(arc
							(start -0.2794 -0.1778)
							(mid -0.249642 -0.249642)
							(end -0.1778 -0.2794)
						)
						(arc
							(start 0.1778 -0.2794)
							(mid 0.249642 -0.249642)
							(end 0.2794 -0.1778)
						)
						(arc
							(start 0.2794 0.1778)
							(mid 0.249642 0.249642)
							(end 0.1778 0.2794)
						)
					)
					(width 0)
					(fill yes)
				)
			)
		)
		(pad "2" smd custom
			(at 0 0.4445 90)
			(size 0.1397 0.1397)
			(layers "B.Cu" "B.Mask" "B.Paste")
			(net "COMP_PWR_EN")
			(options
				(clearance outline)
				(anchor circle)
			)
			(primitives
				(gr_poly
					(pts
						(arc
							(start -0.1778 0.2794)
							(mid -0.249642 0.249642)
							(end -0.2794 0.1778)
						)
						(arc
							(start -0.2794 -0.1778)
							(mid -0.249642 -0.249642)
							(end -0.1778 -0.2794)
						)
						(arc
							(start 0.1778 -0.2794)
							(mid 0.249642 -0.249642)
							(end 0.2794 -0.1778)
						)
						(arc
							(start 0.2794 0.1778)
							(mid 0.249642 0.249642)
							(end 0.1778 0.2794)
						)
					)
					(width 0)
					(fill yes)
				)
			)
		)
	)
	(footprint ""
		(layer "B.Cu")
		(at 43.9928 -133.7818 -90)
		(property "Reference" "R184"
			(at 0 0 90)
			(layer "B.SilkS")
			(hide yes)
			(effects
				(font
					(size 1.27 1.27)
				)
				(justify mirror)
			)
		)
		(property "Value" "2K2R2F-GP"
			(at -0.064008 -3.993896 270)
			(unlocked yes)
			(layer "B.Fab")
			(hide yes)
			(effects
				(font
					(size 1.016 1.016)
					(thickness 0.1524)
				)
				(justify mirror)
			)
		)
		(property "Device Type" "R402H16"
			(at -0.064008 -5.517896 270)
			(unlocked yes)
			(layer "B.Fab")
			(hide yes)
			(effects
				(font
					(size 1.016 1.016)
					(thickness 0.1524)
				)
				(justify mirror)
			)
		)
		(duplicate_pad_numbers_are_jumpers no)
		(fp_line
			(start -0.508 -0.9398)
			(end 0.508 -0.9398)
			(stroke
				(width 0.1524)
				(type default)
			)
			(layer "B.SilkS")
		)
		(fp_line
			(start 0.508 -0.9398)
			(end 0.508 0.9398)
			(stroke
				(width 0.1524)
				(type default)
			)
			(layer "B.SilkS")
		)
		(fp_rect
			(start 0.508 0.9398)
			(end -0.508 -0.9398)
			(stroke
				(width 0)
				(type default)
			)
			(fill no)
			(layer "B.CrtYd")
		)
		(fp_rect
			(start 0.508 0.9398)
			(end -0.508 -0.9398)
			(stroke
				(width 0)
				(type default)
			)
			(fill no)
			(layer "B.Fab")
		)
		(pad "1" smd custom
			(at 0 -0.4445 90)
			(size 0.1397 0.1397)
			(layers "B.Cu" "B.Mask" "B.Paste")
			(net "I2C_IOM_SDA")
			(options
				(clearance outline)
				(anchor circle)
			)
			(primitives
				(gr_poly
					(pts
						(arc
							(start -0.1778 0.2794)
							(mid -0.249642 0.249642)
							(end -0.2794 0.1778)
						)
						(arc
							(start -0.2794 -0.1778)
							(mid -0.249642 -0.249642)
							(end -0.1778 -0.2794)
						)
						(arc
							(start 0.1778 -0.2794)
							(mid 0.249642 -0.249642)
							(end 0.2794 -0.1778)
						)
						(arc
							(start 0.2794 0.1778)
							(mid 0.249642 0.249642)
							(end 0.1778 0.2794)
						)
					)
					(width 0)
					(fill yes)
				)
			)
		)
		(pad "2" smd custom
			(at 0 0.4445 90)
			(size 0.1397 0.1397)
			(layers "B.Cu" "B.Mask" "B.Paste")
			(net "P3V3_STBY")
			(options
				(clearance outline)
				(anchor circle)
			)
			(primitives
				(gr_poly
					(pts
						(arc
							(start -0.1778 0.2794)
							(mid -0.249642 0.249642)
							(end -0.2794 0.1778)
						)
						(arc
							(start -0.2794 -0.1778)
							(mid -0.249642 -0.249642)
							(end -0.1778 -0.2794)
						)
						(arc
							(start 0.1778 -0.2794)
							(mid 0.249642 -0.249642)
							(end 0.2794 -0.1778)
						)
						(arc
							(start 0.2794 0.1778)
							(mid 0.249642 0.249642)
							(end 0.1778 0.2794)
						)
					)
					(width 0)
					(fill yes)
				)
			)
		)
	)
)
